(kicad_pcb
	(version 20260206)
	(generator "pcbnew")
	(generator_version "10.0")
	(general
		(thickness 1.6)
		(legacy_teardrops no)
	)
	(paper "A4")
	(title_block
		(title "Wiwynn_Tioga_Pass_MB.brd")
		(comment 1 "Tioga Pass / footprint 997 of 4770 (EU8F2), pads 1-41 of 41")
	)
	(layers
		(0 "F.Cu" signal "TOP")
		(4 "In1.Cu" signal "L2GND")
		(6 "In2.Cu" signal "L3")
		(8 "In3.Cu" signal "L4GND")
		(10 "In4.Cu" signal "L5")
		(12 "In5.Cu" signal "L6GND")
		(14 "In6.Cu" signal "L7VCC")
		(16 "In7.Cu" signal "L8VCC")
		(18 "In8.Cu" signal "L9GND")
		(20 "In9.Cu" signal "L10")
		(22 "In10.Cu" signal "L11GND")
		(24 "In11.Cu" signal "L12")
		(26 "In12.Cu" signal "L13GND")
		(2 "B.Cu" signal "BOTTOM")
		(9 "F.Adhes" user "F.Adhesive")
		(11 "B.Adhes" user "B.Adhesive")
		(13 "F.Paste" user "Package Geometry/Pastemask Top")
		(15 "B.Paste" user "Package Geometry/Pastemask Bottom")
		(5 "F.SilkS" user "Ref Des/Silkscreen Top")
		(7 "B.SilkS" user "Ref Des/Silkscreen Bottom")
		(1 "F.Mask" user "Board Geometry/Soldermask Top")
		(3 "B.Mask" user "Board Geometry/Soldermask Bottom")
		(17 "Dwgs.User" user "User.Drawings")
		(19 "Cmts.User" user "User.Comments")
		(21 "Eco1.User" user "User.Eco1")
		(23 "Eco2.User" user "User.Eco2")
		(25 "Edge.Cuts" user "Board Geometry/Outline")
		(27 "Margin" user)
		(31 "F.CrtYd" user "Package Geometry/Place Bound Top")
		(29 "B.CrtYd" user "Package Geometry/Place Bound Bottom")
		(35 "F.Fab" user "Ref Des/Assembly Top")
		(33 "B.Fab" user "Ref Des/Assembly Bottom")
	)
	(footprint ""
		(layer "F.Cu")
		(at 475.64802 -27.7495 90)
		(property "Reference" "EU8F2"
			(at 8.88365 7.29996 180)
			(unlocked yes)
			(layer "F.SilkS")
			(effects
				(font
					(size 0.7874 0.5842)
					(thickness 0.1524)
				)
			)
		)
		(property "Value" ""
			(at 0 0 90)
			(layer "F.Fab")
			(effects
				(font
					(size 1.27 1.27)
				)
			)
		)
		(duplicate_pad_numbers_are_jumpers no)
		(pad "1" smd custom
			(at 0 0 90)
			(size 0.0762 0.0762)
			(layers "F.Cu" "F.Mask" "F.Paste")
			(net "GND")
			(options
				(clearance outline)
				(anchor circle)
			)
			(primitives
				(gr_poly
					(pts
						(xy -0.5715 -0.1524)
						(arc
							(start 0.4191 -0.1524)
							(mid 0.5715 0)
							(end 0.4191 0.1524)
						)
						(xy -0.5715 0.1524)
					)
					(width 0)
					(fill yes)
				)
			)
		)
		(pad "2" smd custom
			(at 0 0.50038 90)
			(size 0.0762 0.0762)
			(layers "F.Cu" "F.Mask" "F.Paste")
			(net "P3V3_STBY_MNG")
			(options
				(clearance outline)
				(anchor circle)
			)
			(primitives
				(gr_poly
					(pts
						(xy -0.5715 -0.1524)
						(arc
							(start 0.4191 -0.1524)
							(mid 0.5715 0)
							(end 0.4191 0.1524)
						)
						(xy -0.5715 0.1524)
					)
					(width 0)
					(fill yes)
				)
			)
		)
		(pad "3" smd custom
			(at 0 1.00076 90)
			(size 0.0762 0.0762)
			(layers "F.Cu" "F.Mask" "F.Paste")
			(net "TP_CLK_96M_CKMNG_P")
			(options
				(clearance outline)
				(anchor circle)
			)
			(primitives
				(gr_poly
					(pts
						(xy -0.5715 -0.1524)
						(arc
							(start 0.4191 -0.1524)
							(mid 0.5715 0)
							(end 0.4191 0.1524)
						)
						(xy -0.5715 0.1524)
					)
					(width 0)
					(fill yes)
				)
			)
		)
		(pad "4" smd custom
			(at 0 1.50114 90)
			(size 0.0762 0.0762)
			(layers "F.Cu" "F.Mask" "F.Paste")
			(net "TP_CLK_96M_CKMNG_N")
			(options
				(clearance outline)
				(anchor circle)
			)
			(primitives
				(gr_poly
					(pts
						(xy -0.5715 -0.1524)
						(arc
							(start 0.4191 -0.1524)
							(mid 0.5715 0)
							(end 0.4191 0.1524)
						)
						(xy -0.5715 0.1524)
					)
					(width 0)
					(fill yes)
				)
			)
		)
		(pad "5" smd custom
			(at 0 2.00152 90)
			(size 0.0762 0.0762)
			(layers "F.Cu" "F.Mask" "F.Paste")
			(net "PD_CKMNG_OE")
			(options
				(clearance outline)
				(anchor circle)
			)
			(primitives
				(gr_poly
					(pts
						(xy -0.5715 -0.1524)
						(arc
							(start 0.4191 -0.1524)
							(mid 0.5715 0)
							(end 0.4191 0.1524)
						)
						(xy -0.5715 0.1524)
					)
					(width 0)
					(fill yes)
				)
			)
		)
		(pad "6" smd custom
			(at 0 2.5019 90)
			(size 0.0762 0.0762)
			(layers "F.Cu" "F.Mask" "F.Paste")
			(net "PD_CKMNG_OE")
			(options
				(clearance outline)
				(anchor circle)
			)
			(primitives
				(gr_poly
					(pts
						(xy -0.5715 -0.1524)
						(arc
							(start 0.4191 -0.1524)
							(mid 0.5715 0)
							(end 0.4191 0.1524)
						)
						(xy -0.5715 0.1524)
					)
					(width 0)
					(fill yes)
				)
			)
		)
		(pad "7" smd custom
			(at 0 3.00228 90)
			(size 0.0762 0.0762)
			(layers "F.Cu" "F.Mask" "F.Paste")
			(net "TP_CLK_100M_R_DP")
			(options
				(clearance outline)
				(anchor circle)
			)
			(primitives
				(gr_poly
					(pts
						(xy -0.5715 -0.1524)
						(arc
							(start 0.4191 -0.1524)
							(mid 0.5715 0)
							(end 0.4191 0.1524)
						)
						(xy -0.5715 0.1524)
					)
					(width 0)
					(fill yes)
				)
			)
		)
		(pad "8" smd custom
			(at 0 3.50266 90)
			(size 0.0762 0.0762)
			(layers "F.Cu" "F.Mask" "F.Paste")
			(net "TP_CLK_100M_R_DN")
			(options
				(clearance outline)
				(anchor circle)
			)
			(primitives
				(gr_poly
					(pts
						(xy -0.5715 -0.1524)
						(arc
							(start 0.4191 -0.1524)
							(mid 0.5715 0)
							(end 0.4191 0.1524)
						)
						(xy -0.5715 0.1524)
					)
					(width 0)
					(fill yes)
				)
			)
		)
		(pad "9" smd custom
			(at 0 4.00304 90)
			(size 0.0762 0.0762)
			(layers "F.Cu" "F.Mask" "F.Paste")
			(net "P3V3_STBY_MNG_CPU")
			(options
				(clearance outline)
				(anchor circle)
			)
			(primitives
				(gr_poly
					(pts
						(xy -0.5715 -0.1524)
						(arc
							(start 0.4191 -0.1524)
							(mid 0.5715 0)
							(end 0.4191 0.1524)
						)
						(xy -0.5715 0.1524)
					)
					(width 0)
					(fill yes)
				)
			)
		)
		(pad "10" smd custom
			(at 0 4.50342 90)
			(size 0.0762 0.0762)
			(layers "F.Cu" "F.Mask" "F.Paste")
			(net "GND")
			(options
				(clearance outline)
				(anchor circle)
			)
			(primitives
				(gr_poly
					(pts
						(xy -0.5715 -0.1524)
						(arc
							(start 0.4191 -0.1524)
							(mid 0.5715 0)
							(end 0.4191 0.1524)
						)
						(xy -0.5715 0.1524)
					)
					(width 0)
					(fill yes)
				)
			)
		)
		(pad "11" smd custom
			(at 0.85852 5.36448 90)
			(size 0.0762 0.0762)
			(layers "F.Cu" "F.Mask" "F.Paste")
			(net "A_COMP_CKMNG")
			(options
				(clearance outline)
				(anchor circle)
			)
			(primitives
				(gr_poly
					(pts
						(xy -0.1524 0.5715)
						(arc
							(start -0.1524 -0.4191)
							(mid 0 -0.5715)
							(end 0.1524 -0.4191)
						)
						(xy 0.1524 0.5715)
					)
					(width 0)
					(fill yes)
				)
			)
		)
		(pad "12" smd custom
			(at 1.3589 5.36448 90)
			(size 0.0762 0.0762)
			(layers "F.Cu" "F.Mask" "F.Paste")
			(net "P3V3_STBY_MNG")
			(options
				(clearance outline)
				(anchor circle)
			)
			(primitives
				(gr_poly
					(pts
						(xy -0.1524 0.5715)
						(arc
							(start -0.1524 -0.4191)
							(mid 0 -0.5715)
							(end 0.1524 -0.4191)
						)
						(xy 0.1524 0.5715)
					)
					(width 0)
					(fill yes)
				)
			)
		)
		(pad "13" smd custom
			(at 1.85928 5.36448 90)
			(size 0.0762 0.0762)
			(layers "F.Cu" "F.Mask" "F.Paste")
			(net "CLK_32K_SUSCLK_PLD_R")
			(options
				(clearance outline)
				(anchor circle)
			)
			(primitives
				(gr_poly
					(pts
						(xy -0.1524 0.5715)
						(arc
							(start -0.1524 -0.4191)
							(mid 0 -0.5715)
							(end 0.1524 -0.4191)
						)
						(xy 0.1524 0.5715)
					)
					(width 0)
					(fill yes)
				)
			)
		)
		(pad "14" smd custom
			(at 2.35966 5.36448 90)
			(size 0.0762 0.0762)
			(layers "F.Cu" "F.Mask" "F.Paste")
			(net "GND")
			(options
				(clearance outline)
				(anchor circle)
			)
			(primitives
				(gr_poly
					(pts
						(xy -0.1524 0.5715)
						(arc
							(start -0.1524 -0.4191)
							(mid 0 -0.5715)
							(end 0.1524 -0.4191)
						)
						(xy 0.1524 0.5715)
					)
					(width 0)
					(fill yes)
				)
			)
		)
		(pad "15" smd custom
			(at 2.86004 5.36448 90)
			(size 0.0762 0.0762)
			(layers "F.Cu" "F.Mask" "F.Paste")
			(net "P3V3_STBY_MNG")
			(options
				(clearance outline)
				(anchor circle)
			)
			(primitives
				(gr_poly
					(pts
						(xy -0.1524 0.5715)
						(arc
							(start -0.1524 -0.4191)
							(mid 0 -0.5715)
							(end 0.1524 -0.4191)
						)
						(xy 0.1524 0.5715)
					)
					(width 0)
					(fill yes)
				)
			)
		)
		(pad "16" smd custom
			(at 3.36042 5.36448 90)
			(size 0.0762 0.0762)
			(layers "F.Cu" "F.Mask" "F.Paste")
			(net "CLK_25M_BMC_R")
			(options
				(clearance outline)
				(anchor circle)
			)
			(primitives
				(gr_poly
					(pts
						(xy -0.1524 0.5715)
						(arc
							(start -0.1524 -0.4191)
							(mid 0 -0.5715)
							(end 0.1524 -0.4191)
						)
						(xy 0.1524 0.5715)
					)
					(width 0)
					(fill yes)
				)
			)
		)
		(pad "17" smd custom
			(at 3.8608 5.36448 90)
			(size 0.0762 0.0762)
			(layers "F.Cu" "F.Mask" "F.Paste")
			(net "CLK_25M_CPLD_R")
			(options
				(clearance outline)
				(anchor circle)
			)
			(primitives
				(gr_poly
					(pts
						(xy -0.1524 0.5715)
						(arc
							(start -0.1524 -0.4191)
							(mid 0 -0.5715)
							(end 0.1524 -0.4191)
						)
						(xy 0.1524 0.5715)
					)
					(width 0)
					(fill yes)
				)
			)
		)
		(pad "18" smd custom
			(at 4.36118 5.36448 90)
			(size 0.0762 0.0762)
			(layers "F.Cu" "F.Mask" "F.Paste")
			(net "GND")
			(options
				(clearance outline)
				(anchor circle)
			)
			(primitives
				(gr_poly
					(pts
						(xy -0.1524 0.5715)
						(arc
							(start -0.1524 -0.4191)
							(mid 0 -0.5715)
							(end 0.1524 -0.4191)
						)
						(xy 0.1524 0.5715)
					)
					(width 0)
					(fill yes)
				)
			)
		)
		(pad "19" smd custom
			(at 4.86156 5.36448 90)
			(size 0.0762 0.0762)
			(layers "F.Cu" "F.Mask" "F.Paste")
			(net "XTAL_CK_MNG_IN")
			(options
				(clearance outline)
				(anchor circle)
			)
			(primitives
				(gr_poly
					(pts
						(xy -0.1524 0.5715)
						(arc
							(start -0.1524 -0.4191)
							(mid 0 -0.5715)
							(end 0.1524 -0.4191)
						)
						(xy 0.1524 0.5715)
					)
					(width 0)
					(fill yes)
				)
			)
		)
		(pad "20" smd custom
			(at 5.36194 5.36448 90)
			(size 0.0762 0.0762)
			(layers "F.Cu" "F.Mask" "F.Paste")
			(net "XTAL_CK_MNG_OUT_R")
			(options
				(clearance outline)
				(anchor circle)
			)
			(primitives
				(gr_poly
					(pts
						(xy -0.1524 0.5715)
						(arc
							(start -0.1524 -0.4191)
							(mid 0 -0.5715)
							(end 0.1524 -0.4191)
						)
						(xy 0.1524 0.5715)
					)
					(width 0)
					(fill yes)
				)
			)
		)
		(pad "21" smd custom
			(at 6.223 4.50342 90)
			(size 0.0762 0.0762)
			(layers "F.Cu" "F.Mask" "F.Paste")
			(net "GND")
			(options
				(clearance outline)
				(anchor circle)
			)
			(primitives
				(gr_poly
					(pts
						(xy 0.5715 0.1524)
						(arc
							(start -0.4191 0.1524)
							(mid -0.5715 0)
							(end -0.4191 -0.1524)
						)
						(xy 0.5715 -0.1524)
					)
					(width 0)
					(fill yes)
				)
			)
		)
		(pad "22" smd custom
			(at 6.223 4.00304 90)
			(size 0.0762 0.0762)
			(layers "F.Cu" "F.Mask" "F.Paste")
			(net "PU_33P_33M_SMBADR")
			(options
				(clearance outline)
				(anchor circle)
			)
			(primitives
				(gr_poly
					(pts
						(xy 0.5715 0.1524)
						(arc
							(start -0.4191 0.1524)
							(mid -0.5715 0)
							(end -0.4191 -0.1524)
						)
						(xy 0.5715 -0.1524)
					)
					(width 0)
					(fill yes)
				)
			)
		)
		(pad "23" smd custom
			(at 6.223 3.50266 90)
			(size 0.0762 0.0762)
			(layers "F.Cu" "F.Mask" "F.Paste")
			(net "P3V3_STBY_MNG")
			(options
				(clearance outline)
				(anchor circle)
			)
			(primitives
				(gr_poly
					(pts
						(xy 0.5715 0.1524)
						(arc
							(start -0.4191 0.1524)
							(mid -0.5715 0)
							(end -0.4191 -0.1524)
						)
						(xy 0.5715 -0.1524)
					)
					(width 0)
					(fill yes)
				)
			)
		)
		(pad "24" smd custom
			(at 6.223 3.00228 90)
			(size 0.0762 0.0762)
			(layers "F.Cu" "F.Mask" "F.Paste")
			(net "TP_CLK5_50M_CKMNG")
			(options
				(clearance outline)
				(anchor circle)
			)
			(primitives
				(gr_poly
					(pts
						(xy 0.5715 0.1524)
						(arc
							(start -0.4191 0.1524)
							(mid -0.5715 0)
							(end -0.4191 -0.1524)
						)
						(xy 0.5715 -0.1524)
					)
					(width 0)
					(fill yes)
				)
			)
		)
		(pad "25" smd custom
			(at 6.223 2.5019 90)
			(size 0.0762 0.0762)
			(layers "F.Cu" "F.Mask" "F.Paste")
			(net "CLK_50M_CKMNG_PCH_10GBE_R")
			(options
				(clearance outline)
				(anchor circle)
			)
			(primitives
				(gr_poly
					(pts
						(xy 0.5715 0.1524)
						(arc
							(start -0.4191 0.1524)
							(mid -0.5715 0)
							(end -0.4191 -0.1524)
						)
						(xy 0.5715 -0.1524)
					)
					(width 0)
					(fill yes)
				)
			)
		)
		(pad "26" smd custom
			(at 6.223 2.00152 90)
			(size 0.0762 0.0762)
			(layers "F.Cu" "F.Mask" "F.Paste")
			(net "P3V3_STBY_MNG_RMII")
			(options
				(clearance outline)
				(anchor circle)
			)
			(primitives
				(gr_poly
					(pts
						(xy 0.5715 0.1524)
						(arc
							(start -0.4191 0.1524)
							(mid -0.5715 0)
							(end -0.4191 -0.1524)
						)
						(xy 0.5715 -0.1524)
					)
					(width 0)
					(fill yes)
				)
			)
		)
		(pad "27" smd custom
			(at 6.223 1.50114 90)
			(size 0.0762 0.0762)
			(layers "F.Cu" "F.Mask" "F.Paste")
			(net "GND")
			(options
				(clearance outline)
				(anchor circle)
			)
			(primitives
				(gr_poly
					(pts
						(xy 0.5715 0.1524)
						(arc
							(start -0.4191 0.1524)
							(mid -0.5715 0)
							(end -0.4191 -0.1524)
						)
						(xy 0.5715 -0.1524)
					)
					(width 0)
					(fill yes)
				)
			)
		)
		(pad "28" smd custom
			(at 6.223 1.00076 90)
			(size 0.0762 0.0762)
			(layers "F.Cu" "F.Mask" "F.Paste")
			(net "CLK_50M_CKMNG_SPRVLLE_R")
			(options
				(clearance outline)
				(anchor circle)
			)
			(primitives
				(gr_poly
					(pts
						(xy 0.5715 0.1524)
						(arc
							(start -0.4191 0.1524)
							(mid -0.5715 0)
							(end -0.4191 -0.1524)
						)
						(xy 0.5715 -0.1524)
					)
					(width 0)
					(fill yes)
				)
			)
		)
		(pad "29" smd custom
			(at 6.223 0.50038 90)
			(size 0.0762 0.0762)
			(layers "F.Cu" "F.Mask" "F.Paste")
			(net "CLK_50M_CKMNG_BMC_2_R")
			(options
				(clearance outline)
				(anchor circle)
			)
			(primitives
				(gr_poly
					(pts
						(xy 0.5715 0.1524)
						(arc
							(start -0.4191 0.1524)
							(mid -0.5715 0)
							(end -0.4191 -0.1524)
						)
						(xy 0.5715 -0.1524)
					)
					(width 0)
					(fill yes)
				)
			)
		)
		(pad "30" smd custom
			(at 6.223 0 90)
			(size 0.0762 0.0762)
			(layers "F.Cu" "F.Mask" "F.Paste")
			(net "GND")
			(options
				(clearance outline)
				(anchor circle)
			)
			(primitives
				(gr_poly
					(pts
						(xy 0.5715 0.1524)
						(arc
							(start -0.4191 0.1524)
							(mid -0.5715 0)
							(end -0.4191 -0.1524)
						)
						(xy 0.5715 -0.1524)
					)
					(width 0)
					(fill yes)
				)
			)
		)
		(pad "31" smd custom
			(at 5.36194 -0.85852 90)
			(size 0.0762 0.0762)
			(layers "F.Cu" "F.Mask" "F.Paste")
			(net "P3V3_STBY_MNG_RMII")
			(options
				(clearance outline)
				(anchor circle)
			)
			(primitives
				(gr_poly
					(pts
						(xy 0.1524 -0.5715)
						(arc
							(start 0.1524 0.4191)
							(mid 0 0.5715)
							(end -0.1524 0.4191)
						)
						(xy -0.1524 -0.5715)
					)
					(width 0)
					(fill yes)
				)
			)
		)
		(pad "32" smd custom
			(at 4.86156 -0.85852 90)
			(size 0.0762 0.0762)
			(layers "F.Cu" "F.Mask" "F.Paste")
			(net "CLK_50M_CKMNG_BMC_1_R")
			(options
				(clearance outline)
				(anchor circle)
			)
			(primitives
				(gr_poly
					(pts
						(xy 0.1524 -0.5715)
						(arc
							(start 0.1524 0.4191)
							(mid 0 0.5715)
							(end -0.1524 0.4191)
						)
						(xy -0.1524 -0.5715)
					)
					(width 0)
					(fill yes)
				)
			)
		)
		(pad "33" smd custom
			(at 4.36118 -0.85852 90)
			(size 0.0762 0.0762)
			(layers "F.Cu" "F.Mask" "F.Paste")
			(net "CLK_50M_CKMNG_OCP_R")
			(options
				(clearance outline)
				(anchor circle)
			)
			(primitives
				(gr_poly
					(pts
						(xy 0.1524 -0.5715)
						(arc
							(start 0.1524 0.4191)
							(mid 0 0.5715)
							(end -0.1524 0.4191)
						)
						(xy -0.1524 -0.5715)
					)
					(width 0)
					(fill yes)
				)
			)
		)
		(pad "34" smd custom
			(at 3.8608 -0.85852 90)
			(size 0.0762 0.0762)
			(layers "F.Cu" "F.Mask" "F.Paste")
			(net "P3V3_STBY_MNG_RGMII")
			(options
				(clearance outline)
				(anchor circle)
			)
			(primitives
				(gr_poly
					(pts
						(xy 0.1524 -0.5715)
						(arc
							(start 0.1524 0.4191)
							(mid 0 0.5715)
							(end -0.1524 0.4191)
						)
						(xy -0.1524 -0.5715)
					)
					(width 0)
					(fill yes)
				)
			)
		)
		(pad "35" smd custom
			(at 3.36042 -0.85852 90)
			(size 0.0762 0.0762)
			(layers "F.Cu" "F.Mask" "F.Paste")
			(net "GND")
			(options
				(clearance outline)
				(anchor circle)
			)
			(primitives
				(gr_poly
					(pts
						(xy 0.1524 -0.5715)
						(arc
							(start 0.1524 0.4191)
							(mid 0 0.5715)
							(end -0.1524 0.4191)
						)
						(xy -0.1524 -0.5715)
					)
					(width 0)
					(fill yes)
				)
			)
		)
		(pad "36" smd custom
			(at 2.86004 -0.85852 90)
			(size 0.0762 0.0762)
			(layers "F.Cu" "F.Mask" "F.Paste")
			(net "TP_CLK_125M")
			(options
				(clearance outline)
				(anchor circle)
			)
			(primitives
				(gr_poly
					(pts
						(xy 0.1524 -0.5715)
						(arc
							(start 0.1524 0.4191)
							(mid 0 0.5715)
							(end -0.1524 0.4191)
						)
						(xy -0.1524 -0.5715)
					)
					(width 0)
					(fill yes)
				)
			)
		)
		(pad "37" smd custom
			(at 2.35966 -0.85852 90)
			(size 0.0762 0.0762)
			(layers "F.Cu" "F.Mask" "F.Paste")
			(net "TP_CLK_125M_BMCA")
			(options
				(clearance outline)
				(anchor circle)
			)
			(primitives
				(gr_poly
					(pts
						(xy 0.1524 -0.5715)
						(arc
							(start 0.1524 0.4191)
							(mid 0 0.5715)
							(end -0.1524 0.4191)
						)
						(xy -0.1524 -0.5715)
					)
					(width 0)
					(fill yes)
				)
			)
		)
		(pad "38" smd custom
			(at 1.85928 -0.85852 90)
			(size 0.0762 0.0762)
			(layers "F.Cu" "F.Mask" "F.Paste")
			(net "SMB_HOST_STBY_LVC3_SCL_R4")
			(options
				(clearance outline)
				(anchor circle)
			)
			(primitives
				(gr_poly
					(pts
						(xy 0.1524 -0.5715)
						(arc
							(start 0.1524 0.4191)
							(mid 0 0.5715)
							(end -0.1524 0.4191)
						)
						(xy -0.1524 -0.5715)
					)
					(width 0)
					(fill yes)
				)
			)
		)
		(pad "39" smd custom
			(at 1.3589 -0.85852 90)
			(size 0.0762 0.0762)
			(layers "F.Cu" "F.Mask" "F.Paste")
			(net "SMB_HOST_STBY_LVC3_SDA_R4")
			(options
				(clearance outline)
				(anchor circle)
			)
			(primitives
				(gr_poly
					(pts
						(xy 0.1524 -0.5715)
						(arc
							(start 0.1524 0.4191)
							(mid 0 0.5715)
							(end -0.1524 0.4191)
						)
						(xy -0.1524 -0.5715)
					)
					(width 0)
					(fill yes)
				)
			)
		)
		(pad "40" smd custom
			(at 0.85852 -0.85852 90)
			(size 0.0762 0.0762)
			(layers "F.Cu" "F.Mask" "F.Paste")
			(net "PWRGD_P3V3_STBY")
			(options
				(clearance outline)
				(anchor circle)
			)
			(primitives
				(gr_poly
					(pts
						(xy 0.1524 -0.5715)
						(arc
							(start 0.1524 0.4191)
							(mid 0 0.5715)
							(end -0.1524 0.4191)
						)
						(xy -0.1524 -0.5715)
					)
					(width 0)
					(fill yes)
				)
			)
		)
		(pad "41" smd rect
			(at 3.1115 2.25298 90)
			(size 4.0894 4.0894)
			(layers "F.Cu" "F.Mask" "F.Paste")
			(net "GND")
		)
	)
)
